# S9S_MB_2U (Grand Teton) — schematic netlist excerpt (pin names and nets, part order shuffled) for the footprints in the layout excerpt that follows; sources: Cadence DE-HDL packaged netlist, KiCad conversion of 03242023_DA0F0TMBIJ0_F0T_Motherboard_J_brd_V01_OCP.brd

PC260_P0_6  Q_CAP  22UF 16V 20% X6S  pkg C0805  page 269 : A = SW_P12V_PVCCIN_CPU0_FLT ; B = GND
R1196  Q_RES  4.75K 1% CHIP  pkg 0402LF  page 208 : A = FM_CK440_MXCK_25M_100M ; B = GND
R1736  Q_RES  33.2 1% CHIP  pkg 0402LF  page 182 : A = FM_PCH_SLP_SUS_N ; B = FM_SLP_SUS_RSM_RST_N

(kicad_pcb
	(version 20260206)
	(generator "pcbnew")
	(generator_version "10.0")
	(general
		(thickness 1.6)
		(legacy_teardrops no)
	)
	(paper "A4")
	(title_block
		(title "03242023_DA0F0TMBIJ0_F0T_Motherboard_J_brd_V01_OCP.brd")
		(comment 1 "Grand Teton / footprints 4728-4730 of 6105")
	)
	(layers
		(0 "F.Cu" signal "TOP")
		(4 "In1.Cu" signal "GND")
		(6 "In2.Cu" signal "IN1")
		(8 "In3.Cu" signal "GND1")
		(10 "In4.Cu" signal "IN2")
		(12 "In5.Cu" signal "GND2")
		(14 "In6.Cu" signal "IN3")
		(16 "In7.Cu" signal "GND3")
		(18 "In8.Cu" signal "VCC")
		(20 "In9.Cu" signal "VCC1")
		(22 "In10.Cu" signal "GND4")
		(24 "In11.Cu" signal "IN4")
		(26 "In12.Cu" signal "GND5")
		(28 "In13.Cu" signal "IN5")
		(30 "In14.Cu" signal "GND6")
		(32 "In15.Cu" signal "IN6")
		(34 "In16.Cu" signal "GND7")
		(2 "B.Cu" signal "BOTTOM")
		(9 "F.Adhes" user "F.Adhesive")
		(11 "B.Adhes" user "B.Adhesive")
		(13 "F.Paste" user "Package Geometry/Pastemask Top")
		(15 "B.Paste" user "Package Geometry/Pastemask Bottom")
		(5 "F.SilkS" user "Ref Des/Silkscreen Top")
		(7 "B.SilkS" user "Ref Des/Silkscreen Bottom")
		(1 "F.Mask" user "Board Geometry/Soldermask Top")
		(3 "B.Mask" user "Board Geometry/Soldermask Bottom")
		(17 "Dwgs.User" user "User.Drawings")
		(19 "Cmts.User" user "User.Comments")
		(21 "Eco1.User" user "User.Eco1")
		(23 "Eco2.User" user "User.Eco2")
		(25 "Edge.Cuts" user "Board Geometry/Outline")
		(27 "Margin" user)
		(31 "F.CrtYd" user "Package Geometry/Place Bound Top")
		(29 "B.CrtYd" user "Package Geometry/Place Bound Bottom")
		(35 "F.Fab" user "Ref Des/Assembly Top")
		(33 "B.Fab" user "Ref Des/Assembly Bottom")
	)
	(footprint ""
		(layer "B.Cu")
		(at 258.384802 -106.819192 180)
		(property "Reference" "R1196"
			(at 0 0 0)
			(layer "B.SilkS")
			(hide yes)
			(effects
				(font
					(size 1.27 1.27)
				)
				(justify mirror)
			)
		)
		(property "Value" ""
			(at 0 0 0)
			(layer "B.Fab")
			(effects
				(font
					(size 1.27 1.27)
				)
				(justify mirror)
			)
		)
		(duplicate_pad_numbers_are_jumpers no)
		(fp_line
			(start 0.7874 0.4064)
			(end 0.7874 -0.4064)
			(stroke
				(width 0.1524)
				(type default)
			)
			(layer "B.SilkS")
		)
		(fp_line
			(start 0.7874 -0.4064)
			(end -0.7874 -0.4064)
			(stroke
				(width 0.1524)
				(type default)
			)
			(layer "B.SilkS")
		)
		(fp_line
			(start -0.7874 0.4064)
			(end 0.7874 0.4064)
			(stroke
				(width 0.1524)
				(type default)
			)
			(layer "B.SilkS")
		)
		(fp_line
			(start -0.7874 -0.4064)
			(end -0.7874 0.4064)
			(stroke
				(width 0.1524)
				(type default)
			)
			(layer "B.SilkS")
		)
		(fp_line
			(start 0.67945 0.3048)
			(end 0.67945 -0.305054)
			(stroke
				(width 0.1)
				(type default)
			)
			(layer "B.Fab")
		)
		(fp_line
			(start 0.67945 -0.305054)
			(end 0.12065 -0.305054)
			(stroke
				(width 0.1)
				(type default)
			)
			(layer "B.Fab")
		)
		(fp_line
			(start 0.12065 0.3048)
			(end 0.67945 0.3048)
			(stroke
				(width 0.1)
				(type default)
			)
			(layer "B.Fab")
		)
		(fp_line
			(start 0.12065 0.2794)
			(end 0.12065 0.3048)
			(stroke
				(width 0.1)
				(type default)
			)
			(layer "B.Fab")
		)
		(fp_line
			(start 0.12065 -0.2794)
			(end -0.12065 -0.2794)
			(stroke
				(width 0.1)
				(type default)
			)
			(layer "B.Fab")
		)
		(fp_line
			(start 0.12065 -0.305054)
			(end 0.12065 -0.2794)
			(stroke
				(width 0.1)
				(type default)
			)
			(layer "B.Fab")
		)
		(fp_line
			(start -0.120396 0.3048)
			(end -0.120396 0.2794)
			(stroke
				(width 0.1)
				(type default)
			)
			(layer "B.Fab")
		)
		(fp_line
			(start -0.120396 0.2794)
			(end 0.12065 0.2794)
			(stroke
				(width 0.1)
				(type default)
			)
			(layer "B.Fab")
		)
		(fp_line
			(start -0.12065 -0.2794)
			(end -0.12065 -0.3048)
			(stroke
				(width 0.1)
				(type default)
			)
			(layer "B.Fab")
		)
		(fp_line
			(start -0.12065 -0.3048)
			(end -0.67945 -0.3048)
			(stroke
				(width 0.1)
				(type default)
			)
			(layer "B.Fab")
		)
		(fp_line
			(start -0.67945 0.3048)
			(end -0.120396 0.3048)
			(stroke
				(width 0.1)
				(type default)
			)
			(layer "B.Fab")
		)
		(fp_line
			(start -0.67945 -0.3048)
			(end -0.67945 0.3048)
			(stroke
				(width 0.1)
				(type default)
			)
			(layer "B.Fab")
		)
		(pad "1" smd circle
			(at 0.40005 0)
			(size 0 0)
			(layers "B.Cu" "B.Mask" "B.Paste")
			(net "FM_CK440_MXCK_25M_100M")
		)
		(pad "2" smd circle
			(at -0.40005 0)
			(size 0 0)
			(layers "B.Cu" "B.Mask" "B.Paste")
			(net "GND")
		)
	)
	(footprint ""
		(layer "B.Cu")
		(at 340.033864 -337.145884 90)
		(property "Reference" "PC260_P0_6"
			(at 0 0 90)
			(layer "B.SilkS")
			(hide yes)
			(effects
				(font
					(size 1.27 1.27)
				)
				(justify mirror)
			)
		)
		(property "Value" ""
			(at 0 0 90)
			(layer "B.Fab")
			(effects
				(font
					(size 1.27 1.27)
				)
				(justify mirror)
			)
		)
		(duplicate_pad_numbers_are_jumpers no)
		(fp_line
			(start 1.524 -0.762)
			(end -1.524 -0.762)
			(stroke
				(width 0.1524)
				(type default)
			)
			(layer "B.SilkS")
		)
		(fp_line
			(start -1.524 -0.762)
			(end -1.524 0.762)
			(stroke
				(width 0.1524)
				(type default)
			)
			(layer "B.SilkS")
		)
		(fp_line
			(start 1.524 0.762)
			(end 1.524 -0.762)
			(stroke
				(width 0.1524)
				(type default)
			)
			(layer "B.SilkS")
		)
		(fp_line
			(start -1.524 0.762)
			(end 1.524 0.762)
			(stroke
				(width 0.1524)
				(type default)
			)
			(layer "B.SilkS")
		)
		(fp_line
			(start 1.1049 -0.724916)
			(end 1.1049 0.724916)
			(stroke
				(width 0.1)
				(type default)
			)
			(layer "B.Fab")
		)
		(fp_line
			(start -1.1049 -0.724916)
			(end 1.1049 -0.724916)
			(stroke
				(width 0.1)
				(type default)
			)
			(layer "B.Fab")
		)
		(fp_line
			(start 1.1049 0.724916)
			(end -1.1049 0.724916)
			(stroke
				(width 0.1)
				(type default)
			)
			(layer "B.Fab")
		)
		(fp_line
			(start -1.1049 0.724916)
			(end -1.1049 -0.724916)
			(stroke
				(width 0.1)
				(type default)
			)
			(layer "B.Fab")
		)
		(pad "1" smd rect
			(at 0.889 0 90)
			(size 1.016 1.27)
			(layers "B.Cu" "B.Mask" "B.Paste")
			(net "SW_P12V_PVCCIN_CPU0_FLT")
		)
		(pad "2" smd rect
			(at -0.889 0 90)
			(size 1.016 1.27)
			(layers "B.Cu" "B.Mask" "B.Paste")
			(net "GND")
		)
	)
	(footprint ""
		(layer "B.Cu")
		(at 322.080382 -38.794944 45)
		(property "Reference" "R1736"
			(at 0 0 45)
			(layer "B.SilkS")
			(hide yes)
			(effects
				(font
					(size 1.27 1.27)
				)
				(justify mirror)
			)
		)
		(property "Value" ""
			(at 0 0 45)
			(layer "B.Fab")
			(effects
				(font
					(size 1.27 1.27)
				)
				(justify mirror)
			)
		)
		(duplicate_pad_numbers_are_jumpers no)
		(fp_line
			(start -0.787389 -0.406267)
			(end -0.787389 0.406267)
			(stroke
				(width 0.1524)
				(type default)
			)
			(layer "B.SilkS")
		)
		(fp_line
			(start -0.787389 0.406267)
			(end 0.787389 0.406267)
			(stroke
				(width 0.1524)
				(type default)
			)
			(layer "B.SilkS")
		)
		(fp_line
			(start 0.787389 -0.406267)
			(end -0.787389 -0.406267)
			(stroke
				(width 0.1524)
				(type default)
			)
			(layer "B.SilkS")
		)
		(fp_line
			(start 0.787389 0.406267)
			(end 0.787389 -0.406267)
			(stroke
				(width 0.1524)
				(type default)
			)
			(layer "B.SilkS")
		)
		(fp_line
			(start -0.679446 -0.30479)
			(end -0.679446 0.30479)
			(stroke
				(width 0.1)
				(type default)
			)
			(layer "B.Fab")
		)
		(fp_line
			(start -0.120515 -0.30479)
			(end -0.679446 -0.30479)
			(stroke
				(width 0.1)
				(type default)
			)
			(layer "B.Fab")
		)
		(fp_line
			(start -0.120695 -0.279466)
			(end -0.120515 -0.30479)
			(stroke
				(width 0.1)
				(type default)
			)
			(layer "B.Fab")
		)
		(fp_line
			(start -0.679446 0.30479)
			(end -0.120515 0.30479)
			(stroke
				(width 0.1)
				(type default)
			)
			(layer "B.Fab")
		)
		(fp_line
			(start 0.120695 -0.304969)
			(end 0.120695 -0.279466)
			(stroke
				(width 0.1)
				(type default)
			)
			(layer "B.Fab")
		)
		(fp_line
			(start 0.120695 -0.279466)
			(end -0.120695 -0.279466)
			(stroke
				(width 0.1)
				(type default)
			)
			(layer "B.Fab")
		)
		(fp_line
			(start -0.120335 0.279466)
			(end 0.120695 0.279466)
			(stroke
				(width 0.1)
				(type default)
			)
			(layer "B.Fab")
		)
		(fp_line
			(start -0.120515 0.30479)
			(end -0.120335 0.279466)
			(stroke
				(width 0.1)
				(type default)
			)
			(layer "B.Fab")
		)
		(fp_line
			(start 0.679446 -0.305149)
			(end 0.120695 -0.304969)
			(stroke
				(width 0.1)
				(type default)
			)
			(layer "B.Fab")
		)
		(fp_line
			(start 0.120695 0.279466)
			(end 0.120515 0.30479)
			(stroke
				(width 0.1)
				(type default)
			)
			(layer "B.Fab")
		)
		(fp_line
			(start 0.120515 0.30479)
			(end 0.679446 0.30479)
			(stroke
				(width 0.1)
				(type default)
			)
			(layer "B.Fab")
		)
		(fp_line
			(start 0.679446 0.30479)
			(end 0.679446 -0.305149)
			(stroke
				(width 0.1)
				(type default)
			)
			(layer "B.Fab")
		)
		(pad "1" smd circle
			(at 0.40005 0 225)
			(size 0 0)
			(layers "B.Cu" "B.Mask" "B.Paste")
			(net "FM_PCH_SLP_SUS_N")
		)
		(pad "2" smd circle
			(at -0.40005 0 225)
			(size 0 0)
			(layers "B.Cu" "B.Mask" "B.Paste")
			(net "FM_SLP_SUS_RSM_RST_N")
		)
	)
)
